# T6G (Grand Teton) — schematic netlist excerpt (pin names and nets, part order shuffled) for the footprints in the layout excerpt that follows; sources: Cadence DE-HDL packaged netlist, KiCad conversion of 04192023_DAF0TMB3IC0_F0TG_MB_C_brd_V02_OCP.brd

R573  Q_RES  0 5% CHIP  pkg 0402LF  page 55 : A = CLK_CPU0_RTCCLK ; B = XTAL_CPU1_X32K_X1
C130  Q_CAP  0.1UF 10V 10% X7S  pkg C0201  page 323 : A = P1V8_CPU1_RT0_1A_1D ; B = GND
R3176  Q_RES  1K 1% CHIP  pkg 0402LF  page 137 : A = SGPIO_OCP_V3_2_CLK ; B = P3V3_OCP_V3_2

(kicad_pcb
	(version 20260206)
	(generator "pcbnew")
	(generator_version "10.0")
	(general
		(thickness 1.6)
		(legacy_teardrops no)
	)
	(paper "A4")
	(title_block
		(title "04192023_DAF0TMB3IC0_F0TG_MB_C_brd_V02_OCP.brd")
		(comment 1 "Grand Teton / footprints 5962-5964 of 8354")
	)
	(layers
		(0 "F.Cu" signal "TOP")
		(4 "In1.Cu" signal "GND")
		(6 "In2.Cu" signal "IN1")
		(8 "In3.Cu" signal "GND1")
		(10 "In4.Cu" signal "IN2")
		(12 "In5.Cu" signal "GND2")
		(14 "In6.Cu" signal "IN3")
		(16 "In7.Cu" signal "GND3")
		(18 "In8.Cu" signal "VCC")
		(20 "In9.Cu" signal "VCC1")
		(22 "In10.Cu" signal "GND4")
		(24 "In11.Cu" signal "IN4")
		(26 "In12.Cu" signal "GND5")
		(28 "In13.Cu" signal "IN5")
		(30 "In14.Cu" signal "GND6")
		(32 "In15.Cu" signal "IN6")
		(34 "In16.Cu" signal "GND7")
		(2 "B.Cu" signal "BOTTOM")
		(9 "F.Adhes" user "F.Adhesive")
		(11 "B.Adhes" user "B.Adhesive")
		(13 "F.Paste" user "Package Geometry/Pastemask Top")
		(15 "B.Paste" user "Package Geometry/Pastemask Bottom")
		(5 "F.SilkS" user "Ref Des/Silkscreen Top")
		(7 "B.SilkS" user "Ref Des/Silkscreen Bottom")
		(1 "F.Mask" user "Board Geometry/Soldermask Top")
		(3 "B.Mask" user "Board Geometry/Soldermask Bottom")
		(17 "Dwgs.User" user "User.Drawings")
		(19 "Cmts.User" user "User.Comments")
		(21 "Eco1.User" user "User.Eco1")
		(23 "Eco2.User" user "User.Eco2")
		(25 "Edge.Cuts" user "Board Geometry/Outline")
		(27 "Margin" user)
		(31 "F.CrtYd" user "Package Geometry/Place Bound Top")
		(29 "B.CrtYd" user "Package Geometry/Place Bound Bottom")
		(35 "F.Fab" user "Ref Des/Assembly Top")
		(33 "B.Fab" user "Ref Des/Assembly Bottom")
	)
	(footprint ""
		(layer "B.Cu")
		(at 73.841864 -11.26871 90)
		(property "Reference" "R3176"
			(at 0 0 90)
			(layer "B.SilkS")
			(hide yes)
			(effects
				(font
					(size 1.27 1.27)
				)
				(justify mirror)
			)
		)
		(property "Value" ""
			(at 0 0 90)
			(layer "B.Fab")
			(effects
				(font
					(size 1.27 1.27)
				)
				(justify mirror)
			)
		)
		(duplicate_pad_numbers_are_jumpers no)
		(fp_line
			(start 0.7874 -0.4064)
			(end -0.7874 -0.4064)
			(stroke
				(width 0.1524)
				(type default)
			)
			(layer "B.SilkS")
		)
		(fp_line
			(start -0.7874 -0.4064)
			(end -0.7874 0.4064)
			(stroke
				(width 0.1524)
				(type default)
			)
			(layer "B.SilkS")
		)
		(fp_line
			(start 0.7874 0.4064)
			(end 0.7874 -0.4064)
			(stroke
				(width 0.1524)
				(type default)
			)
			(layer "B.SilkS")
		)
		(fp_line
			(start -0.7874 0.4064)
			(end 0.7874 0.4064)
			(stroke
				(width 0.1524)
				(type default)
			)
			(layer "B.SilkS")
		)
		(fp_line
			(start 0.67945 -0.305054)
			(end 0.12065 -0.305054)
			(stroke
				(width 0.1)
				(type default)
			)
			(layer "B.Fab")
		)
		(fp_line
			(start 0.12065 -0.305054)
			(end 0.12065 -0.2794)
			(stroke
				(width 0.1)
				(type default)
			)
			(layer "B.Fab")
		)
		(fp_line
			(start -0.12065 -0.3048)
			(end -0.67945 -0.3048)
			(stroke
				(width 0.1)
				(type default)
			)
			(layer "B.Fab")
		)
		(fp_line
			(start -0.67945 -0.3048)
			(end -0.67945 0.3048)
			(stroke
				(width 0.1)
				(type default)
			)
			(layer "B.Fab")
		)
		(fp_line
			(start 0.12065 -0.2794)
			(end -0.12065 -0.2794)
			(stroke
				(width 0.1)
				(type default)
			)
			(layer "B.Fab")
		)
		(fp_line
			(start -0.12065 -0.2794)
			(end -0.12065 -0.3048)
			(stroke
				(width 0.1)
				(type default)
			)
			(layer "B.Fab")
		)
		(fp_line
			(start 0.12065 0.2794)
			(end 0.12065 0.3048)
			(stroke
				(width 0.1)
				(type default)
			)
			(layer "B.Fab")
		)
		(fp_line
			(start -0.120396 0.2794)
			(end 0.12065 0.2794)
			(stroke
				(width 0.1)
				(type default)
			)
			(layer "B.Fab")
		)
		(fp_line
			(start 0.67945 0.3048)
			(end 0.67945 -0.305054)
			(stroke
				(width 0.1)
				(type default)
			)
			(layer "B.Fab")
		)
		(fp_line
			(start 0.12065 0.3048)
			(end 0.67945 0.3048)
			(stroke
				(width 0.1)
				(type default)
			)
			(layer "B.Fab")
		)
		(fp_line
			(start -0.120396 0.3048)
			(end -0.120396 0.2794)
			(stroke
				(width 0.1)
				(type default)
			)
			(layer "B.Fab")
		)
		(fp_line
			(start -0.67945 0.3048)
			(end -0.120396 0.3048)
			(stroke
				(width 0.1)
				(type default)
			)
			(layer "B.Fab")
		)
		(pad "1" smd circle
			(at 0.40005 0 270)
			(size 0 0)
			(layers "B.Cu" "B.Mask" "B.Paste")
			(net "SGPIO_OCP_V3_2_CLK")
		)
		(pad "2" smd circle
			(at -0.40005 0 270)
			(size 0 0)
			(layers "B.Cu" "B.Mask" "B.Paste")
			(net "P3V3_OCP_V3_2")
		)
	)
	(footprint ""
		(layer "B.Cu")
		(at 58.3184 -388.011162 -90)
		(property "Reference" "C130"
			(at 0 0 90)
			(layer "B.SilkS")
			(hide yes)
			(effects
				(font
					(size 1.27 1.27)
				)
				(justify mirror)
			)
		)
		(property "Value" ""
			(at 0 0 90)
			(layer "B.Fab")
			(effects
				(font
					(size 1.27 1.27)
				)
				(justify mirror)
			)
		)
		(duplicate_pad_numbers_are_jumpers no)
		(fp_line
			(start -0.299974 0.150114)
			(end 0.299974 0.150114)
			(stroke
				(width 0.1)
				(type default)
			)
			(layer "B.Fab")
		)
		(fp_line
			(start 0.299974 0.150114)
			(end 0.299974 -0.150114)
			(stroke
				(width 0.1)
				(type default)
			)
			(layer "B.Fab")
		)
		(fp_line
			(start -0.299974 -0.150114)
			(end -0.299974 0.150114)
			(stroke
				(width 0.1)
				(type default)
			)
			(layer "B.Fab")
		)
		(fp_line
			(start 0.299974 -0.150114)
			(end -0.299974 -0.150114)
			(stroke
				(width 0.1)
				(type default)
			)
			(layer "B.Fab")
		)
		(pad "1" smd rect
			(at 0.2667 0 90)
			(size 0.3048 0.381)
			(layers "B.Cu" "B.Mask" "B.Paste")
			(net "P1V8_CPU1_RT0_1A_1D")
		)
		(pad "2" smd rect
			(at -0.2667 0 90)
			(size 0.3048 0.381)
			(layers "B.Cu" "B.Mask" "B.Paste")
			(net "GND")
		)
	)
	(footprint ""
		(layer "B.Cu")
		(at 390.020048 -314.180474 -90)
		(property "Reference" "R573"
			(at 0 0 90)
			(layer "B.SilkS")
			(hide yes)
			(effects
				(font
					(size 1.27 1.27)
				)
				(justify mirror)
			)
		)
		(property "Value" ""
			(at 0 0 90)
			(layer "B.Fab")
			(effects
				(font
					(size 1.27 1.27)
				)
				(justify mirror)
			)
		)
		(duplicate_pad_numbers_are_jumpers no)
		(fp_line
			(start -0.7874 0.4064)
			(end 0.7874 0.4064)
			(stroke
				(width 0.1524)
				(type default)
			)
			(layer "B.SilkS")
		)
		(fp_line
			(start 0.7874 0.4064)
			(end 0.7874 -0.4064)
			(stroke
				(width 0.1524)
				(type default)
			)
			(layer "B.SilkS")
		)
		(fp_line
			(start -0.7874 -0.4064)
			(end -0.7874 0.4064)
			(stroke
				(width 0.1524)
				(type default)
			)
			(layer "B.SilkS")
		)
		(fp_line
			(start 0.7874 -0.4064)
			(end -0.7874 -0.4064)
			(stroke
				(width 0.1524)
				(type default)
			)
			(layer "B.SilkS")
		)
		(fp_line
			(start -0.67945 0.3048)
			(end -0.120396 0.3048)
			(stroke
				(width 0.1)
				(type default)
			)
			(layer "B.Fab")
		)
		(fp_line
			(start -0.120396 0.3048)
			(end -0.120396 0.2794)
			(stroke
				(width 0.1)
				(type default)
			)
			(layer "B.Fab")
		)
		(fp_line
			(start 0.12065 0.3048)
			(end 0.67945 0.3048)
			(stroke
				(width 0.1)
				(type default)
			)
			(layer "B.Fab")
		)
		(fp_line
			(start 0.67945 0.3048)
			(end 0.67945 -0.305054)
			(stroke
				(width 0.1)
				(type default)
			)
			(layer "B.Fab")
		)
		(fp_line
			(start -0.120396 0.2794)
			(end 0.12065 0.2794)
			(stroke
				(width 0.1)
				(type default)
			)
			(layer "B.Fab")
		)
		(fp_line
			(start 0.12065 0.2794)
			(end 0.12065 0.3048)
			(stroke
				(width 0.1)
				(type default)
			)
			(layer "B.Fab")
		)
		(fp_line
			(start -0.12065 -0.2794)
			(end -0.12065 -0.3048)
			(stroke
				(width 0.1)
				(type default)
			)
			(layer "B.Fab")
		)
		(fp_line
			(start 0.12065 -0.2794)
			(end -0.12065 -0.2794)
			(stroke
				(width 0.1)
				(type default)
			)
			(layer "B.Fab")
		)
		(fp_line
			(start -0.67945 -0.3048)
			(end -0.67945 0.3048)
			(stroke
				(width 0.1)
				(type default)
			)
			(layer "B.Fab")
		)
		(fp_line
			(start -0.12065 -0.3048)
			(end -0.67945 -0.3048)
			(stroke
				(width 0.1)
				(type default)
			)
			(layer "B.Fab")
		)
		(fp_line
			(start 0.12065 -0.305054)
			(end 0.12065 -0.2794)
			(stroke
				(width 0.1)
				(type default)
			)
			(layer "B.Fab")
		)
		(fp_line
			(start 0.67945 -0.305054)
			(end 0.12065 -0.305054)
			(stroke
				(width 0.1)
				(type default)
			)
			(layer "B.Fab")
		)
		(pad "1" smd circle
			(at 0.40005 0 90)
			(size 0 0)
			(layers "B.Cu" "B.Mask" "B.Paste")
			(net "CLK_CPU0_RTCCLK")
		)
		(pad "2" smd circle
			(at -0.40005 0 90)
			(size 0 0)
			(layers "B.Cu" "B.Mask" "B.Paste")
			(net "XTAL_CPU1_X32K_X1")
		)
	)
)
